(kicad_pcb
	(version 20260206)
	(generator "pcbnew")
	(generator_version "10.0")
	(general
		(thickness 1.6)
		(legacy_teardrops no)
	)
	(paper "A4")
	(title_block
		(title "04192023_DAF0TMB3IC0_F0TG_MB_C_brd_V02_OCP.brd")
		(comment 1 "Grand Teton / footprints 1737-1742 of 8354")
	)
	(layers
		(0 "F.Cu" signal "TOP")
		(4 "In1.Cu" signal "GND")
		(6 "In2.Cu" signal "IN1")
		(8 "In3.Cu" signal "GND1")
		(10 "In4.Cu" signal "IN2")
		(12 "In5.Cu" signal "GND2")
		(14 "In6.Cu" signal "IN3")
		(16 "In7.Cu" signal "GND3")
		(18 "In8.Cu" signal "VCC")
		(20 "In9.Cu" signal "VCC1")
		(22 "In10.Cu" signal "GND4")
		(24 "In11.Cu" signal "IN4")
		(26 "In12.Cu" signal "GND5")
		(28 "In13.Cu" signal "IN5")
		(30 "In14.Cu" signal "GND6")
		(32 "In15.Cu" signal "IN6")
		(34 "In16.Cu" signal "GND7")
		(2 "B.Cu" signal "BOTTOM")
		(9 "F.Adhes" user "F.Adhesive")
		(11 "B.Adhes" user "B.Adhesive")
		(13 "F.Paste" user "Package Geometry/Pastemask Top")
		(15 "B.Paste" user "Package Geometry/Pastemask Bottom")
		(5 "F.SilkS" user "Ref Des/Silkscreen Top")
		(7 "B.SilkS" user "Ref Des/Silkscreen Bottom")
		(1 "F.Mask" user "Board Geometry/Soldermask Top")
		(3 "B.Mask" user "Board Geometry/Soldermask Bottom")
		(17 "Dwgs.User" user "User.Drawings")
		(19 "Cmts.User" user "User.Comments")
		(21 "Eco1.User" user "User.Eco1")
		(23 "Eco2.User" user "User.Eco2")
		(25 "Edge.Cuts" user "Board Geometry/Outline")
		(27 "Margin" user)
		(31 "F.CrtYd" user "Package Geometry/Place Bound Top")
		(29 "B.CrtYd" user "Package Geometry/Place Bound Bottom")
		(35 "F.Fab" user "Ref Des/Assembly Top")
		(33 "B.Fab" user "Ref Des/Assembly Bottom")
	)
	(footprint ""
		(layer "F.Cu")
		(at 71.064882 -31.894272 -90)
		(property "Reference" "R1193"
			(at 0 0 270)
			(layer "F.SilkS")
			(hide yes)
			(effects
				(font
					(size 1.27 1.27)
				)
			)
		)
		(property "Value" ""
			(at 0 0 270)
			(layer "F.Fab")
			(effects
				(font
					(size 1.27 1.27)
				)
			)
		)
		(duplicate_pad_numbers_are_jumpers no)
		(fp_line
			(start -0.7874 0.4064)
			(end -0.7874 -0.4064)
			(stroke
				(width 0.1524)
				(type default)
			)
			(layer "F.SilkS")
		)
		(fp_line
			(start 0.7874 0.4064)
			(end -0.7874 0.4064)
			(stroke
				(width 0.1524)
				(type default)
			)
			(layer "F.SilkS")
		)
		(fp_line
			(start -0.7874 -0.4064)
			(end 0.7874 -0.4064)
			(stroke
				(width 0.1524)
				(type default)
			)
			(layer "F.SilkS")
		)
		(fp_line
			(start 0.7874 -0.4064)
			(end 0.7874 0.4064)
			(stroke
				(width 0.1524)
				(type default)
			)
			(layer "F.SilkS")
		)
		(fp_line
			(start -0.67945 0.3048)
			(end -0.67945 -0.305054)
			(stroke
				(width 0.1)
				(type default)
			)
			(layer "F.Fab")
		)
		(fp_line
			(start -0.12065 0.3048)
			(end -0.67945 0.3048)
			(stroke
				(width 0.1)
				(type default)
			)
			(layer "F.Fab")
		)
		(fp_line
			(start 0.120396 0.3048)
			(end 0.120396 0.2794)
			(stroke
				(width 0.1)
				(type default)
			)
			(layer "F.Fab")
		)
		(fp_line
			(start 0.67945 0.3048)
			(end 0.120396 0.3048)
			(stroke
				(width 0.1)
				(type default)
			)
			(layer "F.Fab")
		)
		(fp_line
			(start -0.12065 0.2794)
			(end -0.12065 0.3048)
			(stroke
				(width 0.1)
				(type default)
			)
			(layer "F.Fab")
		)
		(fp_line
			(start 0.120396 0.2794)
			(end -0.12065 0.2794)
			(stroke
				(width 0.1)
				(type default)
			)
			(layer "F.Fab")
		)
		(fp_line
			(start -0.12065 -0.2794)
			(end 0.12065 -0.2794)
			(stroke
				(width 0.1)
				(type default)
			)
			(layer "F.Fab")
		)
		(fp_line
			(start 0.12065 -0.2794)
			(end 0.12065 -0.3048)
			(stroke
				(width 0.1)
				(type default)
			)
			(layer "F.Fab")
		)
		(fp_line
			(start 0.12065 -0.3048)
			(end 0.67945 -0.3048)
			(stroke
				(width 0.1)
				(type default)
			)
			(layer "F.Fab")
		)
		(fp_line
			(start 0.67945 -0.3048)
			(end 0.67945 0.3048)
			(stroke
				(width 0.1)
				(type default)
			)
			(layer "F.Fab")
		)
		(fp_line
			(start -0.67945 -0.305054)
			(end -0.12065 -0.305054)
			(stroke
				(width 0.1)
				(type default)
			)
			(layer "F.Fab")
		)
		(fp_line
			(start -0.12065 -0.305054)
			(end -0.12065 -0.2794)
			(stroke
				(width 0.1)
				(type default)
			)
			(layer "F.Fab")
		)
		(pad "1" smd circle
			(at -0.40005 0 270)
			(size 0 0)
			(layers "F.Cu" "F.Mask" "F.Paste")
			(net "P12V_OCP_V3_2_BUF_EN_R")
		)
		(pad "2" smd circle
			(at 0.40005 0 270)
			(size 0 0)
			(layers "F.Cu" "F.Mask" "F.Paste")
			(net "P12V_OCP_V3_2_EN_2_R3")
		)
	)
	(footprint ""
		(layer "F.Cu")
		(at 223.384364 -75.53071 180)
		(property "Reference" "PR4527"
			(at 0 0 180)
			(layer "F.SilkS")
			(hide yes)
			(effects
				(font
					(size 1.27 1.27)
				)
			)
		)
		(property "Value" ""
			(at 0 0 180)
			(layer "F.Fab")
			(effects
				(font
					(size 1.27 1.27)
				)
			)
		)
		(duplicate_pad_numbers_are_jumpers no)
		(fp_line
			(start 0.7874 0.4064)
			(end -0.7874 0.4064)
			(stroke
				(width 0.1524)
				(type default)
			)
			(layer "F.SilkS")
		)
		(fp_line
			(start 0.7874 -0.4064)
			(end 0.7874 0.4064)
			(stroke
				(width 0.1524)
				(type default)
			)
			(layer "F.SilkS")
		)
		(fp_line
			(start -0.7874 0.4064)
			(end -0.7874 -0.4064)
			(stroke
				(width 0.1524)
				(type default)
			)
			(layer "F.SilkS")
		)
		(fp_line
			(start -0.7874 -0.4064)
			(end 0.7874 -0.4064)
			(stroke
				(width 0.1524)
				(type default)
			)
			(layer "F.SilkS")
		)
		(fp_line
			(start 0.67945 0.3048)
			(end 0.120396 0.3048)
			(stroke
				(width 0.1)
				(type default)
			)
			(layer "F.Fab")
		)
		(fp_line
			(start 0.67945 -0.3048)
			(end 0.67945 0.3048)
			(stroke
				(width 0.1)
				(type default)
			)
			(layer "F.Fab")
		)
		(fp_line
			(start 0.12065 -0.2794)
			(end 0.12065 -0.3048)
			(stroke
				(width 0.1)
				(type default)
			)
			(layer "F.Fab")
		)
		(fp_line
			(start 0.12065 -0.3048)
			(end 0.67945 -0.3048)
			(stroke
				(width 0.1)
				(type default)
			)
			(layer "F.Fab")
		)
		(fp_line
			(start 0.120396 0.3048)
			(end 0.120396 0.2794)
			(stroke
				(width 0.1)
				(type default)
			)
			(layer "F.Fab")
		)
		(fp_line
			(start 0.120396 0.2794)
			(end -0.12065 0.2794)
			(stroke
				(width 0.1)
				(type default)
			)
			(layer "F.Fab")
		)
		(fp_line
			(start -0.12065 0.3048)
			(end -0.67945 0.3048)
			(stroke
				(width 0.1)
				(type default)
			)
			(layer "F.Fab")
		)
		(fp_line
			(start -0.12065 0.2794)
			(end -0.12065 0.3048)
			(stroke
				(width 0.1)
				(type default)
			)
			(layer "F.Fab")
		)
		(fp_line
			(start -0.12065 -0.2794)
			(end 0.12065 -0.2794)
			(stroke
				(width 0.1)
				(type default)
			)
			(layer "F.Fab")
		)
		(fp_line
			(start -0.12065 -0.305054)
			(end -0.12065 -0.2794)
			(stroke
				(width 0.1)
				(type default)
			)
			(layer "F.Fab")
		)
		(fp_line
			(start -0.67945 0.3048)
			(end -0.67945 -0.305054)
			(stroke
				(width 0.1)
				(type default)
			)
			(layer "F.Fab")
		)
		(fp_line
			(start -0.67945 -0.305054)
			(end -0.12065 -0.305054)
			(stroke
				(width 0.1)
				(type default)
			)
			(layer "F.Fab")
		)
		(pad "1" smd circle
			(at -0.40005 0 180)
			(size 0 0)
			(layers "F.Cu" "F.Mask" "F.Paste")
			(net "P3V3_E1S_0_R")
		)
		(pad "2" smd circle
			(at 0.40005 0 180)
			(size 0 0)
			(layers "F.Cu" "F.Mask" "F.Paste")
			(net "P3V3_E1S_GATE_0")
		)
	)
	(footprint ""
		(layer "F.Cu")
		(at 215.956134 -32.857948 180)
		(property "Reference" "R3593"
			(at 0 0 180)
			(layer "F.SilkS")
			(hide yes)
			(effects
				(font
					(size 1.27 1.27)
				)
			)
		)
		(property "Value" ""
			(at 0 0 180)
			(layer "F.Fab")
			(effects
				(font
					(size 1.27 1.27)
				)
			)
		)
		(duplicate_pad_numbers_are_jumpers no)
		(fp_line
			(start 0.7874 0.4064)
			(end -0.7874 0.4064)
			(stroke
				(width 0.1524)
				(type default)
			)
			(layer "F.SilkS")
		)
		(fp_line
			(start 0.7874 -0.4064)
			(end 0.7874 0.4064)
			(stroke
				(width 0.1524)
				(type default)
			)
			(layer "F.SilkS")
		)
		(fp_line
			(start -0.7874 0.4064)
			(end -0.7874 -0.4064)
			(stroke
				(width 0.1524)
				(type default)
			)
			(layer "F.SilkS")
		)
		(fp_line
			(start -0.7874 -0.4064)
			(end 0.7874 -0.4064)
			(stroke
				(width 0.1524)
				(type default)
			)
			(layer "F.SilkS")
		)
		(fp_line
			(start 0.67945 0.3048)
			(end 0.120396 0.3048)
			(stroke
				(width 0.1)
				(type default)
			)
			(layer "F.Fab")
		)
		(fp_line
			(start 0.67945 -0.3048)
			(end 0.67945 0.3048)
			(stroke
				(width 0.1)
				(type default)
			)
			(layer "F.Fab")
		)
		(fp_line
			(start 0.12065 -0.2794)
			(end 0.12065 -0.3048)
			(stroke
				(width 0.1)
				(type default)
			)
			(layer "F.Fab")
		)
		(fp_line
			(start 0.12065 -0.3048)
			(end 0.67945 -0.3048)
			(stroke
				(width 0.1)
				(type default)
			)
			(layer "F.Fab")
		)
		(fp_line
			(start 0.120396 0.3048)
			(end 0.120396 0.2794)
			(stroke
				(width 0.1)
				(type default)
			)
			(layer "F.Fab")
		)
		(fp_line
			(start 0.120396 0.2794)
			(end -0.12065 0.2794)
			(stroke
				(width 0.1)
				(type default)
			)
			(layer "F.Fab")
		)
		(fp_line
			(start -0.12065 0.3048)
			(end -0.67945 0.3048)
			(stroke
				(width 0.1)
				(type default)
			)
			(layer "F.Fab")
		)
		(fp_line
			(start -0.12065 0.2794)
			(end -0.12065 0.3048)
			(stroke
				(width 0.1)
				(type default)
			)
			(layer "F.Fab")
		)
		(fp_line
			(start -0.12065 -0.2794)
			(end 0.12065 -0.2794)
			(stroke
				(width 0.1)
				(type default)
			)
			(layer "F.Fab")
		)
		(fp_line
			(start -0.12065 -0.305054)
			(end -0.12065 -0.2794)
			(stroke
				(width 0.1)
				(type default)
			)
			(layer "F.Fab")
		)
		(fp_line
			(start -0.67945 0.3048)
			(end -0.67945 -0.305054)
			(stroke
				(width 0.1)
				(type default)
			)
			(layer "F.Fab")
		)
		(fp_line
			(start -0.67945 -0.305054)
			(end -0.12065 -0.305054)
			(stroke
				(width 0.1)
				(type default)
			)
			(layer "F.Fab")
		)
		(pad "1" smd circle
			(at -0.40005 0 180)
			(size 0 0)
			(layers "F.Cu" "F.Mask" "F.Paste")
			(net "SMB_INA230_3V3AUX_SDA")
		)
		(pad "2" smd circle
			(at 0.40005 0 180)
			(size 0 0)
			(layers "F.Cu" "F.Mask" "F.Paste")
			(net "SMB_INA230_5_3V3AUX_SDA_R")
		)
	)
	(footprint ""
		(layer "F.Cu")
		(at 270.856202 -351.5487 90)
		(property "Reference" "PR443"
			(at 0 0 90)
			(layer "F.SilkS")
			(hide yes)
			(effects
				(font
					(size 1.27 1.27)
				)
			)
		)
		(property "Value" ""
			(at 0 0 90)
			(layer "F.Fab")
			(effects
				(font
					(size 1.27 1.27)
				)
			)
		)
		(duplicate_pad_numbers_are_jumpers no)
		(fp_line
			(start 0.7874 -0.4064)
			(end 0.7874 0.4064)
			(stroke
				(width 0.1524)
				(type default)
			)
			(layer "F.SilkS")
		)
		(fp_line
			(start -0.7874 -0.4064)
			(end 0.7874 -0.4064)
			(stroke
				(width 0.1524)
				(type default)
			)
			(layer "F.SilkS")
		)
		(fp_line
			(start 0.7874 0.4064)
			(end -0.7874 0.4064)
			(stroke
				(width 0.1524)
				(type default)
			)
			(layer "F.SilkS")
		)
		(fp_line
			(start -0.7874 0.4064)
			(end -0.7874 -0.4064)
			(stroke
				(width 0.1524)
				(type default)
			)
			(layer "F.SilkS")
		)
		(fp_line
			(start -0.12065 -0.305054)
			(end -0.12065 -0.2794)
			(stroke
				(width 0.1)
				(type default)
			)
			(layer "F.Fab")
		)
		(fp_line
			(start -0.67945 -0.305054)
			(end -0.12065 -0.305054)
			(stroke
				(width 0.1)
				(type default)
			)
			(layer "F.Fab")
		)
		(fp_line
			(start 0.67945 -0.3048)
			(end 0.67945 0.3048)
			(stroke
				(width 0.1)
				(type default)
			)
			(layer "F.Fab")
		)
		(fp_line
			(start 0.12065 -0.3048)
			(end 0.67945 -0.3048)
			(stroke
				(width 0.1)
				(type default)
			)
			(layer "F.Fab")
		)
		(fp_line
			(start 0.12065 -0.2794)
			(end 0.12065 -0.3048)
			(stroke
				(width 0.1)
				(type default)
			)
			(layer "F.Fab")
		)
		(fp_line
			(start -0.12065 -0.2794)
			(end 0.12065 -0.2794)
			(stroke
				(width 0.1)
				(type default)
			)
			(layer "F.Fab")
		)
		(fp_line
			(start 0.120396 0.2794)
			(end -0.12065 0.2794)
			(stroke
				(width 0.1)
				(type default)
			)
			(layer "F.Fab")
		)
		(fp_line
			(start -0.12065 0.2794)
			(end -0.12065 0.3048)
			(stroke
				(width 0.1)
				(type default)
			)
			(layer "F.Fab")
		)
		(fp_line
			(start 0.67945 0.3048)
			(end 0.120396 0.3048)
			(stroke
				(width 0.1)
				(type default)
			)
			(layer "F.Fab")
		)
		(fp_line
			(start 0.120396 0.3048)
			(end 0.120396 0.2794)
			(stroke
				(width 0.1)
				(type default)
			)
			(layer "F.Fab")
		)
		(fp_line
			(start -0.12065 0.3048)
			(end -0.67945 0.3048)
			(stroke
				(width 0.1)
				(type default)
			)
			(layer "F.Fab")
		)
		(fp_line
			(start -0.67945 0.3048)
			(end -0.67945 -0.305054)
			(stroke
				(width 0.1)
				(type default)
			)
			(layer "F.Fab")
		)
		(pad "1" smd circle
			(at -0.40005 0 90)
			(size 0 0)
			(layers "F.Cu" "F.Mask" "F.Paste")
			(net "PVDDCR_CPU1_P0_PVCC")
		)
		(pad "2" smd circle
			(at 0.40005 0 90)
			(size 0 0)
			(layers "F.Cu" "F.Mask" "F.Paste")
			(net "P3V3_AUX")
		)
	)
	(footprint ""
		(layer "F.Cu")
		(at 108.458 -417.703 180)
		(property "Reference" "R555"
			(at 0 0 180)
			(layer "F.SilkS")
			(hide yes)
			(effects
				(font
					(size 1.27 1.27)
				)
			)
		)
		(property "Value" ""
			(at 0 0 180)
			(layer "F.Fab")
			(effects
				(font
					(size 1.27 1.27)
				)
			)
		)
		(duplicate_pad_numbers_are_jumpers no)
		(fp_line
			(start 1.2954 0.5842)
			(end -1.2954 0.5842)
			(stroke
				(width 0.1524)
				(type default)
			)
			(layer "F.SilkS")
		)
		(fp_line
			(start 1.2954 -0.5842)
			(end 1.2954 0.5842)
			(stroke
				(width 0.1524)
				(type default)
			)
			(layer "F.SilkS")
		)
		(fp_line
			(start -1.2954 0.5842)
			(end -1.2954 -0.5842)
			(stroke
				(width 0.1524)
				(type default)
			)
			(layer "F.SilkS")
		)
		(fp_line
			(start -1.2954 -0.5842)
			(end 1.2954 -0.5842)
			(stroke
				(width 0.1524)
				(type default)
			)
			(layer "F.SilkS")
		)
		(fp_line
			(start 1.1938 0.4064)
			(end 0.8636 0.4064)
			(stroke
				(width 0.1)
				(type default)
			)
			(layer "F.Fab")
		)
		(fp_line
			(start 1.1938 -0.406654)
			(end 1.1938 0.4064)
			(stroke
				(width 0.1)
				(type default)
			)
			(layer "F.Fab")
		)
		(fp_line
			(start 0.8636 0.4572)
			(end -0.8636 0.4572)
			(stroke
				(width 0.1)
				(type default)
			)
			(layer "F.Fab")
		)
		(fp_line
			(start 0.8636 0.4064)
			(end 0.8636 0.4572)
			(stroke
				(width 0.1)
				(type default)
			)
			(layer "F.Fab")
		)
		(fp_line
			(start 0.8636 -0.406654)
			(end 1.1938 -0.406654)
			(stroke
				(width 0.1)
				(type default)
			)
			(layer "F.Fab")
		)
		(fp_line
			(start 0.8636 -0.4572)
			(end 0.8636 -0.406654)
			(stroke
				(width 0.1)
				(type default)
			)
			(layer "F.Fab")
		)
		(fp_line
			(start -0.8636 0.4572)
			(end -0.8636 0.4318)
			(stroke
				(width 0.1)
				(type default)
			)
			(layer "F.Fab")
		)
		(fp_line
			(start -0.8636 0.4318)
			(end -0.8636 0.4064)
			(stroke
				(width 0.1)
				(type default)
			)
			(layer "F.Fab")
		)
		(fp_line
			(start -0.8636 0.4064)
			(end -1.1938 0.4064)
			(stroke
				(width 0.1)
				(type default)
			)
			(layer "F.Fab")
		)
		(fp_line
			(start -0.8636 -0.406654)
			(end -0.8636 -0.4572)
			(stroke
				(width 0.1)
				(type default)
			)
			(layer "F.Fab")
		)
		(fp_line
			(start -0.8636 -0.4572)
			(end 0.8636 -0.4572)
			(stroke
				(width 0.1)
				(type default)
			)
			(layer "F.Fab")
		)
		(fp_line
			(start -1.1938 0.4064)
			(end -1.1938 -0.406654)
			(stroke
				(width 0.1)
				(type default)
			)
			(layer "F.Fab")
		)
		(fp_line
			(start -1.1938 -0.406654)
			(end -0.8636 -0.406654)
			(stroke
				(width 0.1)
				(type default)
			)
			(layer "F.Fab")
		)
		(pad "1" smd rect
			(at -0.7366 0 90)
			(size 0.7112 0.8128)
			(layers "F.Cu" "F.Mask" "F.Paste")
			(net "P3V3_9ZXL045_P1")
		)
		(pad "2" smd rect
			(at 0.7366 0 90)
			(size 0.7112 0.8128)
			(layers "F.Cu" "F.Mask" "F.Paste")
			(net "P3V3_9ZXL045_P1_VDDR")
		)
	)
	(footprint ""
		(layer "F.Cu")
		(at 9.379458 -422.551098)
		(property "Reference" "R6173"
			(at 0 0 0)
			(layer "F.SilkS")
			(hide yes)
			(effects
				(font
					(size 1.27 1.27)
				)
			)
		)
		(property "Value" ""
			(at 0 0 0)
			(layer "F.Fab")
			(effects
				(font
					(size 1.27 1.27)
				)
			)
		)
		(duplicate_pad_numbers_are_jumpers no)
		(fp_line
			(start -0.7874 -0.4064)
			(end 0.7874 -0.4064)
			(stroke
				(width 0.1524)
				(type default)
			)
			(layer "F.SilkS")
		)
		(fp_line
			(start -0.7874 0.4064)
			(end -0.7874 -0.4064)
			(stroke
				(width 0.1524)
				(type default)
			)
			(layer "F.SilkS")
		)
		(fp_line
			(start 0.7874 -0.4064)
			(end 0.7874 0.4064)
			(stroke
				(width 0.1524)
				(type default)
			)
			(layer "F.SilkS")
		)
		(fp_line
			(start 0.7874 0.4064)
			(end -0.7874 0.4064)
			(stroke
				(width 0.1524)
				(type default)
			)
			(layer "F.SilkS")
		)
		(fp_line
			(start -0.67945 -0.305054)
			(end -0.12065 -0.305054)
			(stroke
				(width 0.1)
				(type default)
			)
			(layer "F.Fab")
		)
		(fp_line
			(start -0.67945 0.3048)
			(end -0.67945 -0.305054)
			(stroke
				(width 0.1)
				(type default)
			)
			(layer "F.Fab")
		)
		(fp_line
			(start -0.12065 -0.305054)
			(end -0.12065 -0.2794)
			(stroke
				(width 0.1)
				(type default)
			)
			(layer "F.Fab")
		)
		(fp_line
			(start -0.12065 -0.2794)
			(end 0.12065 -0.2794)
			(stroke
				(width 0.1)
				(type default)
			)
			(layer "F.Fab")
		)
		(fp_line
			(start -0.12065 0.2794)
			(end -0.12065 0.3048)
			(stroke
				(width 0.1)
				(type default)
			)
			(layer "F.Fab")
		)
		(fp_line
			(start -0.12065 0.3048)
			(end -0.67945 0.3048)
			(stroke
				(width 0.1)
				(type default)
			)
			(layer "F.Fab")
		)
		(fp_line
			(start 0.120396 0.2794)
			(end -0.12065 0.2794)
			(stroke
				(width 0.1)
				(type default)
			)
			(layer "F.Fab")
		)
		(fp_line
			(start 0.120396 0.3048)
			(end 0.120396 0.2794)
			(stroke
				(width 0.1)
				(type default)
			)
			(layer "F.Fab")
		)
		(fp_line
			(start 0.12065 -0.3048)
			(end 0.67945 -0.3048)
			(stroke
				(width 0.1)
				(type default)
			)
			(layer "F.Fab")
		)
		(fp_line
			(start 0.12065 -0.2794)
			(end 0.12065 -0.3048)
			(stroke
				(width 0.1)
				(type default)
			)
			(layer "F.Fab")
		)
		(fp_line
			(start 0.67945 -0.3048)
			(end 0.67945 0.3048)
			(stroke
				(width 0.1)
				(type default)
			)
			(layer "F.Fab")
		)
		(fp_line
			(start 0.67945 0.3048)
			(end 0.120396 0.3048)
			(stroke
				(width 0.1)
				(type default)
			)
			(layer "F.Fab")
		)
		(pad "1" smd circle
			(at -0.40005 0)
			(size 0 0)
			(layers "F.Cu" "F.Mask" "F.Paste")
			(net "P3V3_AUX")
		)
		(pad "2" smd circle
			(at 0.40005 0)
			(size 0 0)
			(layers "F.Cu" "F.Mask" "F.Paste")
			(net "FM_P2E_BUF2_EQA0")
		)
	)
)
